FILE_TYPE = MULTI_PHYS_TABLE;
PART 'TPS2061'
{=========================================================================================================================================================================================}
:PACK_TYPE | MATERIAL | PART_NUMBER     = EnvComp | PART_NUMBER  | JEDEC_TYPE  | DESCRIPTION                          | CLASS | COMPONENT_TYPE | HEIGHT      | LPID | SPEED_URL | Status |RPL| AML | Bus_Unit | Days;
{=========================================================================================================================================================================================}
'SM'       | 'IC'     | 'H66405-001'(!) = ''      | 'H66405-001' | 'SOT23_5C'  | 'IC,LIN,ANALOGSWITCH,SOT23,TPS2061D' | 'IC'  | 'SMALLSMT'     | '0.057 IN'  |'1815'| 'http://speed.intel.com:8081/speed/module/pdm/item/pdm_item_detail_direct.asp?item_cde=H66405-001&item_rev=01&url_param=unused' | '' | '' | '' | '' | '' 
'SM'       | 'EMPTY'  | 'H66405-001'(!) = ''      | 'H66405-001' | 'SOT23_5C'  | 'IC,LIN,ANALOGSWITCH,SOT23,TPS2061D' | 'IO'  | 'SMALLSMT'     | '0.057 IN'  |'1815'| 'http://speed.intel.com:8081/speed/module/pdm/item/pdm_item_detail_direct.asp?item_cde=H66405-001&item_rev=01&url_param=unused' | '' | '' | '' | '' | '' 
END_PART
END.
